# S9S_MB_2U (Grand Teton) — schematic netlist excerpt (pin names and nets, part order shuffled) for the footprints in the layout excerpt that follows; sources: Cadence DE-HDL packaged netlist, KiCad conversion of 03242023_DA0F0TMBIJ0_F0T_Motherboard_J_brd_V01_OCP.brd

C893  Q_CAP_DIFFBUS  DIFF BUS_0.22UF 6.3V 20% X6S  pkg C0201  page 174 : \1\ = P5E_CPU0_PE3_TX_C_DP<4> ; \2\ = P5E_CPU0_PE3_TX_DP<4>
R2900  Q_RES  2K 1% EMPTY  pkg 0402LF  page 250 : A = MAX11617_VREF ; B = MAX11617_VREF_R
R2661  Q_RES  33.2 1% CHIP  pkg 0402LF  page 213 : A = FM_SWB_PWR_EN ; B = FM_SWB_PWR_EN_R

(kicad_pcb
	(version 20260206)
	(generator "pcbnew")
	(generator_version "10.0")
	(general
		(thickness 1.6)
		(legacy_teardrops no)
	)
	(paper "A4")
	(title_block
		(title "03242023_DA0F0TMBIJ0_F0T_Motherboard_J_brd_V01_OCP.brd")
		(comment 1 "Grand Teton / footprints 1808-1810 of 6105")
	)
	(layers
		(0 "F.Cu" signal "TOP")
		(4 "In1.Cu" signal "GND")
		(6 "In2.Cu" signal "IN1")
		(8 "In3.Cu" signal "GND1")
		(10 "In4.Cu" signal "IN2")
		(12 "In5.Cu" signal "GND2")
		(14 "In6.Cu" signal "IN3")
		(16 "In7.Cu" signal "GND3")
		(18 "In8.Cu" signal "VCC")
		(20 "In9.Cu" signal "VCC1")
		(22 "In10.Cu" signal "GND4")
		(24 "In11.Cu" signal "IN4")
		(26 "In12.Cu" signal "GND5")
		(28 "In13.Cu" signal "IN5")
		(30 "In14.Cu" signal "GND6")
		(32 "In15.Cu" signal "IN6")
		(34 "In16.Cu" signal "GND7")
		(2 "B.Cu" signal "BOTTOM")
		(9 "F.Adhes" user "F.Adhesive")
		(11 "B.Adhes" user "B.Adhesive")
		(13 "F.Paste" user "Package Geometry/Pastemask Top")
		(15 "B.Paste" user "Package Geometry/Pastemask Bottom")
		(5 "F.SilkS" user "Ref Des/Silkscreen Top")
		(7 "B.SilkS" user "Ref Des/Silkscreen Bottom")
		(1 "F.Mask" user "Board Geometry/Soldermask Top")
		(3 "B.Mask" user "Board Geometry/Soldermask Bottom")
		(17 "Dwgs.User" user "User.Drawings")
		(19 "Cmts.User" user "User.Comments")
		(21 "Eco1.User" user "User.Eco1")
		(23 "Eco2.User" user "User.Eco2")
		(25 "Edge.Cuts" user "Board Geometry/Outline")
		(27 "Margin" user)
		(31 "F.CrtYd" user "Package Geometry/Place Bound Top")
		(29 "B.CrtYd" user "Package Geometry/Place Bound Bottom")
		(35 "F.Fab" user "Ref Des/Assembly Top")
		(33 "B.Fab" user "Ref Des/Assembly Bottom")
	)
	(footprint ""
		(layer "F.Cu")
		(at 32.761428 -102.761034)
		(property "Reference" "R2900"
			(at 0 0 0)
			(layer "F.SilkS")
			(hide yes)
			(effects
				(font
					(size 1.27 1.27)
				)
			)
		)
		(property "Value" ""
			(at 0 0 0)
			(layer "F.Fab")
			(effects
				(font
					(size 1.27 1.27)
				)
			)
		)
		(duplicate_pad_numbers_are_jumpers no)
		(fp_line
			(start -0.7874 -0.4064)
			(end 0.7874 -0.4064)
			(stroke
				(width 0.1524)
				(type default)
			)
			(layer "F.SilkS")
		)
		(fp_line
			(start -0.7874 0.4064)
			(end -0.7874 -0.4064)
			(stroke
				(width 0.1524)
				(type default)
			)
			(layer "F.SilkS")
		)
		(fp_line
			(start 0.7874 -0.4064)
			(end 0.7874 0.4064)
			(stroke
				(width 0.1524)
				(type default)
			)
			(layer "F.SilkS")
		)
		(fp_line
			(start 0.7874 0.4064)
			(end -0.7874 0.4064)
			(stroke
				(width 0.1524)
				(type default)
			)
			(layer "F.SilkS")
		)
		(fp_line
			(start -0.67945 -0.305054)
			(end -0.12065 -0.305054)
			(stroke
				(width 0.1)
				(type default)
			)
			(layer "F.Fab")
		)
		(fp_line
			(start -0.67945 0.3048)
			(end -0.67945 -0.305054)
			(stroke
				(width 0.1)
				(type default)
			)
			(layer "F.Fab")
		)
		(fp_line
			(start -0.12065 -0.305054)
			(end -0.12065 -0.2794)
			(stroke
				(width 0.1)
				(type default)
			)
			(layer "F.Fab")
		)
		(fp_line
			(start -0.12065 -0.2794)
			(end 0.12065 -0.2794)
			(stroke
				(width 0.1)
				(type default)
			)
			(layer "F.Fab")
		)
		(fp_line
			(start -0.12065 0.2794)
			(end -0.12065 0.3048)
			(stroke
				(width 0.1)
				(type default)
			)
			(layer "F.Fab")
		)
		(fp_line
			(start -0.12065 0.3048)
			(end -0.67945 0.3048)
			(stroke
				(width 0.1)
				(type default)
			)
			(layer "F.Fab")
		)
		(fp_line
			(start 0.120396 0.2794)
			(end -0.12065 0.2794)
			(stroke
				(width 0.1)
				(type default)
			)
			(layer "F.Fab")
		)
		(fp_line
			(start 0.120396 0.3048)
			(end 0.120396 0.2794)
			(stroke
				(width 0.1)
				(type default)
			)
			(layer "F.Fab")
		)
		(fp_line
			(start 0.12065 -0.3048)
			(end 0.67945 -0.3048)
			(stroke
				(width 0.1)
				(type default)
			)
			(layer "F.Fab")
		)
		(fp_line
			(start 0.12065 -0.2794)
			(end 0.12065 -0.3048)
			(stroke
				(width 0.1)
				(type default)
			)
			(layer "F.Fab")
		)
		(fp_line
			(start 0.67945 -0.3048)
			(end 0.67945 0.3048)
			(stroke
				(width 0.1)
				(type default)
			)
			(layer "F.Fab")
		)
		(fp_line
			(start 0.67945 0.3048)
			(end 0.120396 0.3048)
			(stroke
				(width 0.1)
				(type default)
			)
			(layer "F.Fab")
		)
		(pad "1" smd circle
			(at -0.40005 0)
			(size 0 0)
			(layers "F.Cu" "F.Mask" "F.Paste")
			(net "MAX11617_VREF")
		)
		(pad "2" smd circle
			(at 0.40005 0)
			(size 0 0)
			(layers "F.Cu" "F.Mask" "F.Paste")
			(net "MAX11617_VREF_R")
		)
	)
	(footprint ""
		(layer "F.Cu")
		(at 407.35377 -408.517344 -90)
		(property "Reference" "C893"
			(at 0 0 270)
			(layer "F.SilkS")
			(hide yes)
			(effects
				(font
					(size 1.27 1.27)
				)
			)
		)
		(property "Value" ""
			(at 0 0 270)
			(layer "F.Fab")
			(effects
				(font
					(size 1.27 1.27)
				)
			)
		)
		(duplicate_pad_numbers_are_jumpers no)
		(fp_line
			(start -0.299974 0.150114)
			(end -0.299974 -0.150114)
			(stroke
				(width 0.1)
				(type default)
			)
			(layer "F.Fab")
		)
		(fp_line
			(start 0.299974 0.150114)
			(end -0.299974 0.150114)
			(stroke
				(width 0.1)
				(type default)
			)
			(layer "F.Fab")
		)
		(fp_line
			(start -0.299974 -0.150114)
			(end 0.299974 -0.150114)
			(stroke
				(width 0.1)
				(type default)
			)
			(layer "F.Fab")
		)
		(fp_line
			(start 0.299974 -0.150114)
			(end 0.299974 0.150114)
			(stroke
				(width 0.1)
				(type default)
			)
			(layer "F.Fab")
		)
		(pad "1" smd rect
			(at -0.2667 0 270)
			(size 0.3048 0.381)
			(layers "F.Cu" "F.Mask" "F.Paste")
			(net "P5E_CPU0_PE3_TX_C_DP<4>")
		)
		(pad "2" smd rect
			(at 0.2667 0 270)
			(size 0.3048 0.381)
			(layers "F.Cu" "F.Mask" "F.Paste")
			(net "P5E_CPU0_PE3_TX_DP<4>")
		)
	)
	(footprint ""
		(layer "F.Cu")
		(at 170.59402 -99.466908)
		(property "Reference" "R2661"
			(at 0 0 0)
			(layer "F.SilkS")
			(hide yes)
			(effects
				(font
					(size 1.27 1.27)
				)
			)
		)
		(property "Value" ""
			(at 0 0 0)
			(layer "F.Fab")
			(effects
				(font
					(size 1.27 1.27)
				)
			)
		)
		(duplicate_pad_numbers_are_jumpers no)
		(fp_line
			(start -0.7874 -0.4064)
			(end 0.7874 -0.4064)
			(stroke
				(width 0.1524)
				(type default)
			)
			(layer "F.SilkS")
		)
		(fp_line
			(start -0.7874 0.4064)
			(end -0.7874 -0.4064)
			(stroke
				(width 0.1524)
				(type default)
			)
			(layer "F.SilkS")
		)
		(fp_line
			(start 0.7874 -0.4064)
			(end 0.7874 0.4064)
			(stroke
				(width 0.1524)
				(type default)
			)
			(layer "F.SilkS")
		)
		(fp_line
			(start 0.7874 0.4064)
			(end -0.7874 0.4064)
			(stroke
				(width 0.1524)
				(type default)
			)
			(layer "F.SilkS")
		)
		(fp_line
			(start -0.67945 -0.305054)
			(end -0.12065 -0.305054)
			(stroke
				(width 0.1)
				(type default)
			)
			(layer "F.Fab")
		)
		(fp_line
			(start -0.67945 0.3048)
			(end -0.67945 -0.305054)
			(stroke
				(width 0.1)
				(type default)
			)
			(layer "F.Fab")
		)
		(fp_line
			(start -0.12065 -0.305054)
			(end -0.12065 -0.2794)
			(stroke
				(width 0.1)
				(type default)
			)
			(layer "F.Fab")
		)
		(fp_line
			(start -0.12065 -0.2794)
			(end 0.12065 -0.2794)
			(stroke
				(width 0.1)
				(type default)
			)
			(layer "F.Fab")
		)
		(fp_line
			(start -0.12065 0.2794)
			(end -0.12065 0.3048)
			(stroke
				(width 0.1)
				(type default)
			)
			(layer "F.Fab")
		)
		(fp_line
			(start -0.12065 0.3048)
			(end -0.67945 0.3048)
			(stroke
				(width 0.1)
				(type default)
			)
			(layer "F.Fab")
		)
		(fp_line
			(start 0.120396 0.2794)
			(end -0.12065 0.2794)
			(stroke
				(width 0.1)
				(type default)
			)
			(layer "F.Fab")
		)
		(fp_line
			(start 0.120396 0.3048)
			(end 0.120396 0.2794)
			(stroke
				(width 0.1)
				(type default)
			)
			(layer "F.Fab")
		)
		(fp_line
			(start 0.12065 -0.3048)
			(end 0.67945 -0.3048)
			(stroke
				(width 0.1)
				(type default)
			)
			(layer "F.Fab")
		)
		(fp_line
			(start 0.12065 -0.2794)
			(end 0.12065 -0.3048)
			(stroke
				(width 0.1)
				(type default)
			)
			(layer "F.Fab")
		)
		(fp_line
			(start 0.67945 -0.3048)
			(end 0.67945 0.3048)
			(stroke
				(width 0.1)
				(type default)
			)
			(layer "F.Fab")
		)
		(fp_line
			(start 0.67945 0.3048)
			(end 0.120396 0.3048)
			(stroke
				(width 0.1)
				(type default)
			)
			(layer "F.Fab")
		)
		(pad "1" smd circle
			(at -0.40005 0)
			(size 0 0)
			(layers "F.Cu" "F.Mask" "F.Paste")
			(net "FM_SWB_PWR_EN")
		)
		(pad "2" smd circle
			(at 0.40005 0)
			(size 0 0)
			(layers "F.Cu" "F.Mask" "F.Paste")
			(net "FM_SWB_PWR_EN_R")
		)
	)
)
